FILE_TYPE = CONNECTIVITY;
{Allegro Design Entry HDL 17.2-2016 S081 (4005846) 1/11/2022}
"PAGE_NUMBER" = 171;
0"NC";
1"GND\g";
2"GND\g";
3"GND\g";
4"GND\g";
5"GND\g";
6"GND\g";
7"GND\g";
8"GND\g";
9"GND\g";
10"GND\g";
11"SW_PVDDCR_CPU0_P0_BOOT6_RC";
12"SW_PVDDCR_CPU0_P0_PH6";
13"SW_PVDDCR_CPU0_P0_SW6";
14"GND\g";
15"GND\g";
16"IND_CPU0_P0_CPL5";
17"IND_CPU0_P0_CPL6";
18"SW_PVDDCR_CPU0_P0_BOOT5_RC";
19"SW_PVDDCR_CPU0_P0_PH5";
20"GND\g";
21"IND_CPU0_P0_CPL6";
22"SW_PVDDCR_CPU0_P0_SW5";
23"SW_PVDDCR_CPU0_P0_SW5_RC";
24"SW_PVDDCR_CPU0_P0_BOOT5";
25"SW_P12V_STBY_PVDDCR_CPU0_P0_FLT\g";
26"NC_PVDDCR_CPU0_P0_GL2_5";
27"NC_PVDDCR_CPU0_P0_GL1_5";
28"NC_PVDDCR_CPU0_P0_DNC5";
29"PVDDCR_CPU0_P0_IMON5";
30"PVDDCR_CPU0_P0_TEMP0";
31"PVDDCR_CPU0_P0_LSET5";
32"PVDDCR_CPU0_P0_VCCS";
33"PVDDCR_CPU0_P0_VCC5";
34"PVDDCR_CPU0_P0_PVCC\g";
35"GND\g";
36"GND\g";
37"SW_PVDDCR_CPU0_P0_BOOT6";
38"SW_P12V_STBY_PVDDCR_CPU0_P0_FLT\g";
39"SW_PVDDCR_CPU0_P0_SW6_RC";
40"PVDDCR_CPU0_P0_VOS6";
41"GND\g";
42"NC_PVDDCR_CPU0_P0_GL2_6";
43"NC_PVDDCR_CPU0_P0_GL1_6";
44"PVDDCR_CPU0_P0_PWM5";
45"PVDDCR_CPU0_P0_VCC6";
46"PVDDCR_CPU0_P0_PVCC\g";
47"PVDDCR_CPU0_P0_PWM6";
48"NC_PVDDCR_CPU0_P0_DNC6";
49"PVDDCR_CPU0_P0_TEMP0";
50"PVDDCR_CPU0_P0_IMON6";
51"PVDDCR_CPU0_P0_LSET6";
52"PVDDCR_CPU0_P0_VCCS";
53"PVDDCR_CPU0_P0_VOS5";
54"PVDDCR_CPU0_P0\g";
55"GND\g";
56"PVDDCR_CPU0_P0\g";
57"IND_CPU0_P0_CPL0";
%"UNIVERSAL_GND"
"1","(-7925,4100)","0","pure_quanta_power","I1";
;
CDS_LIB"pure_quanta_power"
HDL_POWER"GND";
"A"1;
%"Q_RES"
"1","(-7275,4350)","0","pure_quanta","I11";
;
LOCATION"PR353"
$SEC"1"
CDS_SEC"1"
WATTAGE"1/16W"
MATERIAL"EMPTY"
TOLERANCE"1%"
VALUE"8.87K"
PART_NUMBER"CS28872FB01"
PACK_TYPE"0402LF"
CDS_LIB"pure_quanta";
"B"
$PN"2"31;
"A"
$PN"1"4;
%"UNIVERSAL_GND"
"1","(-5550,3925)","0","pure_quanta_power","I15";
;
CDS_LIB"pure_quanta_power"
HDL_POWER"GND";
"A"35;
%"Q_RES"
"1","(-4025,3700)","0","pure_quanta","I17";
;
LOCATION"PR355"
$SEC"1"
CDS_SEC"1"
WATTAGE"1/16W"
MATERIAL"CHIP"
TOLERANCE"5%"
VALUE"0"
PART_NUMBER"CS00002JB38"
PACK_TYPE"0402LF"
CDS_LIB"pure_quanta";
"B"
$PN"2"54;
"A"
$PN"1"53;
%"Q_RES"
"1","(-4675,5000)","0","pure_quanta","I18";
;
LOCATION"PR354"
$SEC"1"
CDS_SEC"1"
PACK_TYPE"0402LF"
TOLERANCE"1%"
MATERIAL"CHIP"
WATTAGE"1/16W"
VALUE"4.7"
PART_NUMBER"CS-4702FB19"
CDS_LIB"pure_quanta";
"B"
$PN"2"18;
"A"
$PN"1"24;
%"Q_CAP"
"1","(-4975,5525)","0","pure_quanta","I19";
;
LOCATION"PC570_5"
$SEC"1"
CDS_SEC"1"
MATERIAL"X6S"
TOLERANCE"10%"
VALUE"1UF"
PART_NUMBER"CH5104KEB02"
VOLTAGE"25V"
PACK_TYPE"C0402"
CDS_LIB"pure_quanta";
"B"
$PN"2"14;
"A"
$PN"1"25;
%"Q_CAP"
"1","(-7925,4375)","0","pure_quanta","I2";
;
LOCATION"PC566_5"
$SEC"1"
CDS_SEC"1"
MATERIAL"X7R"
TOLERANCE"10%"
VALUE"0.1UF"
PART_NUMBER"CH4104K1B00"
VOLTAGE"25V"
PACK_TYPE"0402"
CDS_LIB"pure_quanta";
"B"
$PN"2"1;
"A"
$PN"1"32;
%"Q_CAP"
"1","(-4650,5525)","0","pure_quanta","I20";
;
LOCATION"PC571_5"
$SEC"1"
CDS_SEC"1"
MATERIAL"X6S"
TOLERANCE"10%"
VALUE"10UF"
PART_NUMBER"CH6104KEA00"
VOLTAGE"25V"
PACK_TYPE"C0805"
CDS_LIB"pure_quanta";
"B"
$PN"2"14;
"A"
$PN"1"25;
%"Q_CAP"
"1","(-4300,5525)","0","pure_quanta","I21";
;
LOCATION"PC572_5"
$SEC"1"
CDS_SEC"1"
TOLERANCE"10%"
VALUE"10UF"
VOLTAGE"25V"
PACK_TYPE"C0805"
MATERIAL"X6S"
PART_NUMBER"CH6104KEA00"
CDS_LIB"pure_quanta";
"B"
$PN"2"14;
"A"
$PN"1"25;
%"Q_CAP"
"1","(-3675,4875)","0","pure_quanta","I22";
;
LOCATION"PC574"
$SEC"1"
CDS_SEC"1"
MATERIAL"X7R"
TOLERANCE"10%"
VALUE"0.22UF"
PART_NUMBER"CH4223K1B00"
VOLTAGE"16V"
PACK_TYPE"0402"
CDS_LIB"pure_quanta";
"B"
$PN"2"19;
"A"
$PN"1"18;
%"Q_INDUCTOR4P_14"
"1","(-2875,4525)","0","pure_quanta","I23";
;
LOCATION"PL61"
$SEC"1"
CDS_SEC"1"
PART_NUMBER"CV+15^0TZ04"
MATERIAL"IND"
PART_TYPE"SMLF"
VALUE"150NH"
CDS_LIB"pure_quanta"
NEEDS_NO_SIZE"TRUE";
"1"
$PN"1"22;
"4"
$PN"4"54;
"3"
$PN"3"16;
"2"
$PN"2"17;
%"UNIVERSAL_GND"
"1","(-3950,5175)","0","pure_quanta_power","I24";
;
CDS_LIB"pure_quanta_power"
HDL_POWER"GND";
"A"14;
%"Q_CAP"
"1","(-3950,5525)","0","pure_quanta","I25";
;
LOCATION"PC573_5"
$SEC"1"
CDS_SEC"1"
PART_NUMBER"CH6104KEA00"
MATERIAL"X6S"
TOLERANCE"10%"
VALUE"10UF"
VOLTAGE"25V"
PACK_TYPE"C0805"
CDS_LIB"pure_quanta";
"B"
$PN"2"14;
"A"
$PN"1"25;
%"VCC_CORE"
"1","(-3950,5825)","0","pure_quanta_power","I26";
;
HDL_POWER"SW_P12V_STBY_PVDDCR_CPU0_P0_FLT"
CDS_LIB"pure_quanta_power";
"A"25;
%"Q_CAP"
"1","(-1475,4475)","0","pure_quanta","I30";
;
LOCATION"PC575_5"
$SEC"1"
CDS_SEC"1"
MATERIAL"X6S"
TOLERANCE"20%"
VALUE"22UF"
PART_NUMBER"TMP_QCH622KMEA01"
VOLTAGE"4V"
PACK_TYPE"0805"
CDS_LIB"pure_quanta";
"B"
$PN"2"15;
"A"
$PN"1"54;
%"UNIVERSAL_GND"
"1","(-1050,4125)","0","pure_quanta_power","I31";
;
CDS_LIB"pure_quanta_power"
HDL_POWER"GND";
"A"15;
%"Q_CAP"
"1","(-1050,4475)","0","pure_quanta","I32";
;
LOCATION"PC576_5"
$SEC"1"
CDS_SEC"1"
MATERIAL"X6S"
TOLERANCE"20%"
VALUE"22UF"
PART_NUMBER"TMP_QCH622KMEA01"
VOLTAGE"4V"
PACK_TYPE"0805"
CDS_LIB"pure_quanta";
"B"
$PN"2"15;
"A"
$PN"1"54;
%"VCC_CORE"
"1","(-1050,4800)","0","pure_quanta_power","I33";
;
HDL_POWER"PVDDCR_CPU0_P0"
CDS_LIB"pure_quanta_power";
"A"54;
%"Q_CAP"
"1","(-5350,5525)","0","pure_quanta","I36";
;
LOCATION"PC569_5"
$SEC"1"
CDS_SEC"1"
MATERIAL"X7R"
TOLERANCE"10%"
VALUE"0.1UF"
PART_NUMBER"CH4104K1B00"
VOLTAGE"25V"
PACK_TYPE"0402"
CDS_LIB"pure_quanta";
"B"
$PN"2"14;
"A"
$PN"1"25;
%"Q_CAP"
"1","(-7600,5000)","0","pure_quanta","I37";
;
LOCATION"PC567"
$SEC"1"
CDS_SEC"1"
MATERIAL"X6S"
TOLERANCE"10%"
VALUE"2.2UF"
PART_NUMBER"CH5222KEB01"
VOLTAGE"10V"
PACK_TYPE"C0402"
CDS_LIB"pure_quanta";
"B"
$PN"2"2;
"A"
$PN"1"33;
%"UNIVERSAL_GND"
"1","(-7600,4800)","0","pure_quanta_power","I38";
;
CDS_LIB"pure_quanta_power"
HDL_POWER"GND";
"A"2;
%"UNIVERSAL_GND"
"1","(-7250,5250)","0","pure_quanta_power","I39";
;
CDS_LIB"pure_quanta_power"
HDL_POWER"GND";
"A"3;
%"Q_RES"
"2","(-7600,5500)","0","pure_quanta","I40";
;
LOCATION"PR352"
$SEC"1"
CDS_SEC"1"
WATTAGE"1/16W"
MATERIAL"CHIP"
TOLERANCE"1%"
VALUE"2.2"
PART_NUMBER"CS-2202FB00"
PACK_TYPE"0402LF"
CDS_LIB"pure_quanta";
"A"
$PN"1"34;
"B"
$PN"2"33;
%"Q_CAP"
"1","(-7250,5500)","0","pure_quanta","I41";
;
LOCATION"PC568_C0P0_5"
$SEC"1"
CDS_SEC"1"
MATERIAL"X6S"
TOLERANCE"10%"
VALUE"2.2UF"
PART_NUMBER"CH5222KEB01"
VOLTAGE"10V"
PACK_TYPE"C0402"
CDS_LIB"pure_quanta";
"B"
$PN"2"3;
"A"
$PN"1"34;
%"ISL99390FRZTR5935"
"1","(-6100,4650)","0","pure_quanta","I43";
;
LOCATION"PU48"
$SEC"1"
CDS_SEC"1"
PART_TYPE"SMLF"
MATERIAL"IC"
VALUE"ISL99390FRZ-TR5935"
PART_NUMBER"AL099390004"
CDS_LIB"pure_quanta"
NEEDS_NO_SIZE"TRUE"
CDS_LMAN_SYM_OUTLINE"-300,700,250,-650";
"PGND2"
$PN"7_9-20_24"35;
"GL2"
$PN"41"26;
"GL1"
$PN"6"27;
"DNC"
$PN"31"28;
"EN"
$PN"35"33;
"PGND3"
$PN"40"35;
"VOS"
$PN"1"53;
"VIN2"
$PN"30"25;
"PGND1"
$PN"5"35;
"SW"
$PN"10_19"22;
"LSET"
$PN"37"31;
"IOUT"
$PN"38"29;
"TOUT_FLT"
$PN"36"30;
"PVCC"
$PN"4"34;
"PHASE"
$PN"32"19;
"VIN1"
$PN"25_29"25;
"BOOT"
$PN"33"24;
"AGND"
$PN"2"35;
"VCC"
$PN"3"33;
"REFIN"
$PN"39"32;
"PWM"
$PN"34"44;
%"ISL99390FRZTR5935"
"1","(-6100,1925)","0","pure_quanta","I44";
;
LOCATION"PU10"
$SEC"1"
CDS_SEC"1"
PART_TYPE"SMLF"
MATERIAL"IC"
VALUE"ISL99390FRZ-TR5935"
PART_NUMBER"AL099390004"
CDS_LIB"pure_quanta"
NEEDS_NO_SIZE"TRUE"
CDS_LMAN_SYM_OUTLINE"-300,700,250,-650";
"PGND2"
$PN"7_9-20_24"41;
"GL2"
$PN"41"42;
"GL1"
$PN"6"43;
"DNC"
$PN"31"48;
"EN"
$PN"35"45;
"PGND3"
$PN"40"41;
"VOS"
$PN"1"40;
"VIN2"
$PN"30"38;
"PGND1"
$PN"5"41;
"SW"
$PN"10_19"13;
"LSET"
$PN"37"51;
"IOUT"
$PN"38"50;
"TOUT_FLT"
$PN"36"49;
"PVCC"
$PN"4"46;
"PHASE"
$PN"32"12;
"VIN1"
$PN"25_29"38;
"BOOT"
$PN"33"37;
"AGND"
$PN"2"41;
"VCC"
$PN"3"45;
"REFIN"
$PN"39"52;
"PWM"
$PN"34"47;
%"VCC_CORE"
"1","(-1050,2075)","0","pure_quanta_power","I45";
;
HDL_POWER"PVDDCR_CPU0_P0"
CDS_LIB"pure_quanta_power";
"A"56;
%"Q_CAP"
"1","(-1050,1750)","0","pure_quanta","I46";
;
LOCATION"PC166_6"
$SEC"1"
CDS_SEC"1"
MATERIAL"X6S"
TOLERANCE"20%"
VALUE"22UF"
PART_NUMBER"TMP_QCH622KMEA01"
VOLTAGE"4V"
PACK_TYPE"0805"
CDS_LIB"pure_quanta";
"B"
$PN"2"20;
"A"
$PN"1"56;
%"UNIVERSAL_GND"
"1","(-1050,1400)","0","pure_quanta_power","I47";
;
CDS_LIB"pure_quanta_power"
HDL_POWER"GND";
"A"20;
%"Q_CAP"
"1","(-1475,1750)","0","pure_quanta","I48";
;
LOCATION"PC163_6"
$SEC"1"
CDS_SEC"1"
MATERIAL"X6S"
TOLERANCE"20%"
VALUE"22UF"
PART_NUMBER"TMP_QCH622KMEA01"
VOLTAGE"4V"
PACK_TYPE"0805"
CDS_LIB"pure_quanta";
"B"
$PN"2"20;
"A"
$PN"1"56;
%"UNIVERSAL_GND"
"1","(-7600,4175)","0","pure_quanta_power","I5";
;
CDS_LIB"pure_quanta_power"
HDL_POWER"GND";
"A"4;
%"VCC_CORE"
"1","(-4025,3100)","0","pure_quanta_power","I50";
;
HDL_POWER"SW_P12V_STBY_PVDDCR_CPU0_P0_FLT"
CDS_LIB"pure_quanta_power";
"A"38;
%"Q_CAP"
"1","(-4025,2800)","0","pure_quanta","I51";
;
LOCATION"PC159_6"
$SEC"1"
CDS_SEC"1"
MATERIAL"X6S"
TOLERANCE"10%"
VALUE"10UF"
PART_NUMBER"CH6104KEA00"
VOLTAGE"25V"
PACK_TYPE"C0805"
CDS_LIB"pure_quanta";
"B"
$PN"2"36;
"A"
$PN"1"38;
%"UNIVERSAL_GND"
"1","(-4025,2450)","0","pure_quanta_power","I52";
;
CDS_LIB"pure_quanta_power"
HDL_POWER"GND";
"A"36;
%"Q_INDUCTOR4P_14"
"1","(-2875,1800)","0","pure_quanta","I53";
;
LOCATION"PL70"
$SEC"1"
CDS_SEC"1"
PART_TYPE"SMLF"
MATERIAL"IND"
VALUE"150NH"
PART_NUMBER"CV+15^0TZ04"
NEEDS_NO_SIZE"TRUE"
CDS_LIB"pure_quanta";
"1"
$PN"1"13;
"4"
$PN"4"56;
"3"
$PN"3"21;
"2"
$PN"2"57;
%"Q_CAP"
"1","(-3675,2150)","0","pure_quanta","I54";
;
LOCATION"PC161"
$SEC"1"
CDS_SEC"1"
MATERIAL"X7R"
TOLERANCE"10%"
VALUE"0.22UF"
PART_NUMBER"CH4223K1B00"
VOLTAGE"16V"
PACK_TYPE"0402"
CDS_LIB"pure_quanta";
"B"
$PN"2"12;
"A"
$PN"1"11;
%"Q_CAP"
"1","(-4325,2800)","0","pure_quanta","I56";
;
LOCATION"PC158_6"
$SEC"1"
CDS_SEC"1"
MATERIAL"X6S"
TOLERANCE"10%"
VALUE"10UF"
PART_NUMBER"CH6104KEA00"
VOLTAGE"25V"
PACK_TYPE"C0805"
CDS_LIB"pure_quanta";
"B"
$PN"2"36;
"A"
$PN"1"38;
%"Q_CAP"
"1","(-4650,2800)","0","pure_quanta","I57";
;
LOCATION"PC157_6"
$SEC"1"
CDS_SEC"1"
MATERIAL"X6S"
TOLERANCE"10%"
VALUE"10UF"
PART_NUMBER"CH6104KEA00"
VOLTAGE"25V"
PACK_TYPE"C0805"
CDS_LIB"pure_quanta";
"B"
$PN"2"36;
"A"
$PN"1"38;
%"Q_CAP"
"1","(-4975,2800)","0","pure_quanta","I58";
;
LOCATION"PC154_6"
$SEC"1"
CDS_SEC"1"
MATERIAL"X6S"
TOLERANCE"10%"
VALUE"1UF"
PART_NUMBER"CH5104KEB02"
VOLTAGE"25V"
PACK_TYPE"C0402"
CDS_LIB"pure_quanta";
"B"
$PN"2"36;
"A"
$PN"1"38;
%"Q_RES"
"1","(-4300,875)","0","pure_quanta","I59";
;
LOCATION"PR433"
$SEC"1"
CDS_SEC"1"
WATTAGE"1/16W"
MATERIAL"CHIP"
TOLERANCE"5%"
VALUE"0"
PART_NUMBER"CS00002JB38"
PACK_TYPE"0402LF"
CDS_LIB"pure_quanta";
"B"
$PN"2"56;
"A"
$PN"1"40;
%"Q_RES"
"1","(-4675,2275)","0","pure_quanta","I60";
;
LOCATION"PR432"
$SEC"1"
CDS_SEC"1"
TOLERANCE"1%"
MATERIAL"CHIP"
WATTAGE"1/16W"
PACK_TYPE"0402LF"
VALUE"4.7"
PART_NUMBER"CS-4702FB19"
CDS_LIB"pure_quanta";
"B"
$PN"2"11;
"A"
$PN"1"37;
%"Q_CAP"
"1","(-5350,2800)","0","pure_quanta","I61";
;
LOCATION"PC153_6"
$SEC"1"
CDS_SEC"1"
MATERIAL"X7R"
TOLERANCE"10%"
VALUE"0.1UF"
PART_NUMBER"CH4104K1B00"
VOLTAGE"25V"
PACK_TYPE"0402"
CDS_LIB"pure_quanta";
"B"
$PN"2"36;
"A"
$PN"1"38;
%"Q_CAP"
"1","(-7250,2800)","0","pure_quanta","I63";
;
LOCATION"PC152_C0P0_6"
$SEC"1"
CDS_SEC"1"
MATERIAL"X6S"
TOLERANCE"10%"
VALUE"2.2UF"
PART_NUMBER"CH5222KEB01"
VOLTAGE"10V"
PACK_TYPE"C0402"
CDS_LIB"pure_quanta";
"B"
$PN"2"5;
"A"
$PN"1"46;
%"UNIVERSAL_GND"
"1","(-7250,2525)","0","pure_quanta_power","I64";
;
CDS_LIB"pure_quanta_power"
HDL_POWER"GND";
"A"5;
%"Q_RES"
"2","(-7600,2775)","0","pure_quanta","I65";
;
LOCATION"PR430"
$SEC"1"
CDS_SEC"1"
WATTAGE"1/16W"
MATERIAL"CHIP"
TOLERANCE"1%"
VALUE"2.2"
PART_NUMBER"CS-2202FB00"
PACK_TYPE"0402LF"
CDS_LIB"pure_quanta";
"A"
$PN"1"46;
"B"
$PN"2"45;
%"Q_CAP"
"1","(-7600,2275)","0","pure_quanta","I67";
;
LOCATION"PC151"
$SEC"1"
CDS_SEC"1"
MATERIAL"X6S"
TOLERANCE"10%"
VALUE"2.2UF"
PART_NUMBER"CH5222KEB01"
VOLTAGE"10V"
PACK_TYPE"C0402"
CDS_LIB"pure_quanta";
"B"
$PN"2"6;
"A"
$PN"1"45;
%"UNIVERSAL_GND"
"1","(-7600,2075)","0","pure_quanta_power","I68";
;
CDS_LIB"pure_quanta_power"
HDL_POWER"GND";
"A"6;
%"Q_RES"
"1","(-7275,1625)","0","pure_quanta","I69";
;
LOCATION"PR431"
$SEC"1"
CDS_SEC"1"
WATTAGE"1/16W"
MATERIAL"EMPTY"
TOLERANCE"1%"
VALUE"8.87K"
PART_NUMBER"CS28872FB01"
PACK_TYPE"0402LF"
CDS_LIB"pure_quanta";
"B"
$PN"2"51;
"A"
$PN"1"7;
%"UNIVERSAL_GND"
"1","(-7600,1450)","0","pure_quanta_power","I71";
;
CDS_LIB"pure_quanta_power"
HDL_POWER"GND";
"A"7;
%"Q_CAP"
"1","(-7925,1650)","0","pure_quanta","I72";
;
LOCATION"PC150_6"
$SEC"1"
CDS_SEC"1"
MATERIAL"X7R"
TOLERANCE"10%"
VALUE"0.1UF"
PART_NUMBER"CH4104K1B00"
VOLTAGE"25V"
PACK_TYPE"0402"
CDS_LIB"pure_quanta";
"B"
$PN"2"8;
"A"
$PN"1"52;
%"UNIVERSAL_GND"
"1","(-5550,1200)","0","pure_quanta_power","I73";
;
CDS_LIB"pure_quanta_power"
HDL_POWER"GND";
"A"41;
%"UNIVERSAL_GND"
"1","(-7925,1375)","0","pure_quanta_power","I75";
;
CDS_LIB"pure_quanta_power"
HDL_POWER"GND";
"A"8;
%"Q_CAP"
"1","(-4600,4475)","0","pure_quanta","I77";
;
LOCATION"PC184"
$SEC"1"
CDS_SEC"1"
MATERIAL"EMPTY"
TOLERANCE"10%"
VALUE"560PF"
PART_NUMBER"CH1566K1B09"
VOLTAGE"50V"
PACK_TYPE"C0402"
CDS_LIB"pure_quanta";
"B"
$PN"2"23;
"A"
$PN"1"22;
%"Q_RES"
"2","(-4600,4025)","0","pure_quanta","I78";
;
LOCATION"PR501"
$SEC"1"
CDS_SEC"1"
WATTAGE"1/8W"
MATERIAL"EMPTY"
TOLERANCE"1%"
VALUE"1.5"
PART_NUMBER"CS-1504FB00"
PACK_TYPE"0402LF"
CDS_LIB"pure_quanta";
"A"
$PN"1"23;
"B"
$PN"2"9;
%"UNIVERSAL_GND"
"1","(-4600,3800)","0","pure_quanta_power","I79";
;
CDS_LIB"pure_quanta_power"
HDL_POWER"GND";
"A"9;
%"Q_CAP"
"1","(-4625,1750)","0","pure_quanta","I80";
;
LOCATION"PC182"
$SEC"1"
CDS_SEC"1"
MATERIAL"EMPTY"
PART_NUMBER"CH1566K1B09"
TOLERANCE"10%"
VALUE"560PF"
VOLTAGE"50V"
PACK_TYPE"C0402"
CDS_LIB"pure_quanta";
"B"
$PN"2"39;
"A"
$PN"1"13;
%"Q_RES"
"2","(-4625,1250)","0","pure_quanta","I81";
;
LOCATION"PR500"
$SEC"1"
CDS_SEC"1"
PART_NUMBER"CS-1504FB00"
WATTAGE"1/8W"
MATERIAL"EMPTY"
TOLERANCE"1%"
VALUE"1.5"
PACK_TYPE"0402LF"
CDS_LIB"pure_quanta";
"A"
$PN"1"39;
"B"
$PN"2"10;
%"UNIVERSAL_GND"
"1","(-4625,1025)","0","pure_quanta_power","I82";
;
CDS_LIB"pure_quanta_power"
HDL_POWER"GND";
"A"10;
%"VCC_CORE"
"1","(-7600,5900)","0","pure_quanta_power","I83";
;
HDL_POWER"PVDDCR_CPU0_P0_PVCC"
CDS_LIB"pure_quanta_power";
"A"34;
%"VCC_CORE"
"1","(-7600,3200)","0","pure_quanta_power","I84";
;
HDL_POWER"PVDDCR_CPU0_P0_PVCC"
CDS_LIB"pure_quanta_power";
"A"46;
%"UNIVERSAL_GND"
"1","(-4025,1575)","0","pure_quanta_power","I85";
;
CDS_LIB"pure_quanta_power"
HDL_POWER"GND";
"A"55;
%"Q_INDUCTOR"
"1","(-3850,1700)","0","pure_quanta","I86";
;
LOCATION"PL50"
$SEC"1"
CDS_SEC"1"
PART_NUMBER"CV+22Y0EZ00"
PACK_TYPE"SMLF"
VALUE"0.22UH/33A"
MATERIAL"IND"
NEEDS_NO_SIZE"TRUE"
CDS_LIB"pure_quanta";
"1"
$PN"1"55;
"2"
$PN"2"57;
END.
